# BASEBOARD_FAB2 (Tioga Pass) — schematic netlist excerpt (pin names and nets, part order shuffled) for the footprints in the layout excerpt that follows; sources: Cadence DE-HDL packaged netlist, KiCad conversion of Wiwynn_Tioga_Pass_MB.brd

C2T6  CAP  22UF 6.3V 20% X6S  pkg 0805  page 240 : A = P3V3_STBY ; B = GND
C5G45  CAP_A  22.0UF 4V 20% X6S  pkg 0603V  page 242 : A = PVDDQ_ABC ; B = GND
C9U3  CAP  10UF 16V 10% X6S  pkg 0805  page 224 : A = VR_FET_SW_P12V_STBY_PVDDQ_GHJ ; B = GND
C6W12  CAP  100UF 4V 20% X5R  pkg 0805  page 229 : A = PVTT_GHJ ; B = GND

(kicad_pcb
	(version 20260206)
	(generator "pcbnew")
	(generator_version "10.0")
	(general
		(thickness 1.6)
		(legacy_teardrops no)
	)
	(paper "A4")
	(title_block
		(title "Wiwynn_Tioga_Pass_MB.brd")
		(comment 1 "Tioga Pass / footprints 4157-4160 of 4770")
	)
	(layers
		(0 "F.Cu" signal "TOP")
		(4 "In1.Cu" signal "L2GND")
		(6 "In2.Cu" signal "L3")
		(8 "In3.Cu" signal "L4GND")
		(10 "In4.Cu" signal "L5")
		(12 "In5.Cu" signal "L6GND")
		(14 "In6.Cu" signal "L7VCC")
		(16 "In7.Cu" signal "L8VCC")
		(18 "In8.Cu" signal "L9GND")
		(20 "In9.Cu" signal "L10")
		(22 "In10.Cu" signal "L11GND")
		(24 "In11.Cu" signal "L12")
		(26 "In12.Cu" signal "L13GND")
		(2 "B.Cu" signal "BOTTOM")
		(9 "F.Adhes" user "F.Adhesive")
		(11 "B.Adhes" user "B.Adhesive")
		(13 "F.Paste" user "Package Geometry/Pastemask Top")
		(15 "B.Paste" user "Package Geometry/Pastemask Bottom")
		(5 "F.SilkS" user "Ref Des/Silkscreen Top")
		(7 "B.SilkS" user "Ref Des/Silkscreen Bottom")
		(1 "F.Mask" user "Board Geometry/Soldermask Top")
		(3 "B.Mask" user "Board Geometry/Soldermask Bottom")
		(17 "Dwgs.User" user "User.Drawings")
		(19 "Cmts.User" user "User.Comments")
		(21 "Eco1.User" user "User.Eco1")
		(23 "Eco2.User" user "User.Eco2")
		(25 "Edge.Cuts" user "Board Geometry/Outline")
		(27 "Margin" user)
		(31 "F.CrtYd" user "Package Geometry/Place Bound Top")
		(29 "B.CrtYd" user "Package Geometry/Place Bound Bottom")
		(35 "F.Fab" user "Ref Des/Assembly Top")
		(33 "B.Fab" user "Ref Des/Assembly Bottom")
	)
	(footprint ""
		(layer "B.Cu")
		(at 3.82524 -11.392916 90)
		(property "Reference" "C9U3"
			(at 0 0 90)
			(layer "B.SilkS")
			(hide yes)
			(effects
				(font
					(size 1.27 1.27)
				)
				(justify mirror)
			)
		)
		(property "Value" ""
			(at 0 0 90)
			(layer "B.Fab")
			(effects
				(font
					(size 1.27 1.27)
				)
				(justify mirror)
			)
		)
		(duplicate_pad_numbers_are_jumpers no)
		(fp_rect
			(start -0.7239 -0.2159)
			(end 0.7239 1.9939)
			(stroke
				(width 0)
				(type default)
			)
			(fill no)
			(layer "B.CrtYd")
		)
		(fp_line
			(start 0.7239 -0.2159)
			(end 0.7239 1.9939)
			(stroke
				(width 0.1)
				(type default)
			)
			(layer "B.Fab")
		)
		(fp_line
			(start -0.7239 -0.2159)
			(end 0.7239 -0.2159)
			(stroke
				(width 0.1)
				(type default)
			)
			(layer "B.Fab")
		)
		(fp_line
			(start 0.7239 1.9939)
			(end -0.7239 1.9939)
			(stroke
				(width 0.1)
				(type default)
			)
			(layer "B.Fab")
		)
		(fp_line
			(start -0.7239 1.9939)
			(end -0.7239 -0.2159)
			(stroke
				(width 0.1)
				(type default)
			)
			(layer "B.Fab")
		)
		(pad "1" smd rect
			(at 0 0 270)
			(size 1.27 1.016)
			(layers "B.Cu" "B.Mask" "B.Paste")
			(net "VR_FET_SW_P12V_STBY_PVDDQ_GHJ")
		)
		(pad "2" smd rect
			(at 0 1.778 270)
			(size 1.27 1.016)
			(layers "B.Cu" "B.Mask" "B.Paste")
			(net "GND")
		)
		(zone
			(layer "B.Cu")
			(hatch none 0.5)
			(connect_pads
				(clearance 0)
			)
			(min_thickness 0.25)
			(keepout
				(tracks not_allowed)
				(vias allowed)
				(pads allowed)
				(copperpour not_allowed)
				(footprints allowed)
			)
			(placement
				(enabled no)
				(sheetname "")
			)
			(fill
				(thermal_gap 0.5)
				(thermal_bridge_width 0.5)
				(island_removal_mode 0)
			)
			(polygon
				(pts
					(xy 4.33324 -10.757916) (xy 5.09524 -10.757916) (xy 5.09524 -12.027916) (xy 4.33324 -12.027916)
				)
			)
		)
	)
	(footprint ""
		(layer "B.Cu")
		(at 166.5097 -1.90246 180)
		(property "Reference" "C6W12"
			(at -1.47828 0.78994 270)
			(unlocked yes)
			(layer "B.SilkS")
			(effects
				(font
					(size 0.4064 0.254)
					(thickness 0.1524)
				)
				(justify mirror)
			)
		)
		(property "Value" ""
			(at 0 0 0)
			(layer "B.Fab")
			(effects
				(font
					(size 1.27 1.27)
				)
				(justify mirror)
			)
		)
		(duplicate_pad_numbers_are_jumpers no)
		(fp_poly
			(pts
				(xy 0.7239 -0.2159) (xy -0.7239 -0.2159) (xy -0.7239 1.9939) (xy 0.7239 1.9939)
			)
			(stroke
				(width 0)
				(type default)
			)
			(fill no)
			(layer "B.CrtYd")
		)
		(fp_line
			(start 0.7239 1.9939)
			(end -0.7239 1.9939)
			(stroke
				(width 0.1)
				(type default)
			)
			(layer "B.Fab")
		)
		(fp_line
			(start 0.7239 -0.2159)
			(end 0.7239 1.9939)
			(stroke
				(width 0.1)
				(type default)
			)
			(layer "B.Fab")
		)
		(fp_line
			(start -0.7239 1.9939)
			(end -0.7239 -0.2159)
			(stroke
				(width 0.1)
				(type default)
			)
			(layer "B.Fab")
		)
		(fp_line
			(start -0.7239 -0.2159)
			(end 0.7239 -0.2159)
			(stroke
				(width 0.1)
				(type default)
			)
			(layer "B.Fab")
		)
		(pad "1" smd rect
			(at 0 0)
			(size 1.27 1.016)
			(layers "B.Cu" "B.Mask" "B.Paste")
			(net "PVTT_GHJ")
		)
		(pad "2" smd rect
			(at 0 1.778)
			(size 1.27 1.016)
			(layers "B.Cu" "B.Mask" "B.Paste")
			(net "GND")
		)
		(zone
			(layer "B.Cu")
			(hatch none 0.5)
			(connect_pads
				(clearance 0)
			)
			(min_thickness 0.25)
			(keepout
				(tracks not_allowed)
				(vias allowed)
				(pads allowed)
				(copperpour not_allowed)
				(footprints allowed)
			)
			(placement
				(enabled no)
				(sheetname "")
			)
			(fill
				(thermal_gap 0.5)
				(thermal_bridge_width 0.5)
				(island_removal_mode 0)
			)
			(polygon
				(pts
					(xy 165.8747 -2.41046) (xy 167.1447 -2.41046) (xy 167.1447 -3.17246) (xy 165.8747 -3.17246)
				)
			)
		)
	)
	(footprint ""
		(layer "B.Cu")
		(at 258.1402 -12.827 -90)
		(property "Reference" "C5G45"
			(at -1.14681 0.76708 0)
			(unlocked yes)
			(layer "B.SilkS")
			(effects
				(font
					(size 0.7874 0.5842)
					(thickness 0.1524)
				)
				(justify mirror)
			)
		)
		(property "Value" ""
			(at 0 0 90)
			(layer "B.Fab")
			(effects
				(font
					(size 1.27 1.27)
				)
				(justify mirror)
			)
		)
		(duplicate_pad_numbers_are_jumpers no)
		(fp_rect
			(start -0.4953 -0.2032)
			(end 0.4953 1.6002)
			(stroke
				(width 0)
				(type default)
			)
			(fill no)
			(layer "B.CrtYd")
		)
		(fp_line
			(start -0.4953 1.6002)
			(end 0.4953 1.6002)
			(stroke
				(width 0.1)
				(type default)
			)
			(layer "B.Fab")
		)
		(fp_line
			(start 0.4953 1.6002)
			(end 0.4953 -0.2032)
			(stroke
				(width 0.1)
				(type default)
			)
			(layer "B.Fab")
		)
		(fp_line
			(start -0.4953 -0.2032)
			(end -0.4953 1.6002)
			(stroke
				(width 0.1)
				(type default)
			)
			(layer "B.Fab")
		)
		(fp_line
			(start 0.4953 -0.2032)
			(end -0.4953 -0.2032)
			(stroke
				(width 0.1)
				(type default)
			)
			(layer "B.Fab")
		)
		(pad "1" smd rect
			(at 0 0 90)
			(size 0.762 0.889)
			(layers "B.Cu" "B.Mask" "B.Paste")
			(net "PVDDQ_ABC")
		)
		(pad "2" smd rect
			(at 0 1.397 90)
			(size 0.762 0.889)
			(layers "B.Cu" "B.Mask" "B.Paste")
			(net "GND")
		)
		(zone
			(layer "B.Cu")
			(hatch none 0.5)
			(connect_pads
				(clearance 0)
			)
			(min_thickness 0.25)
			(keepout
				(tracks not_allowed)
				(vias allowed)
				(pads allowed)
				(copperpour not_allowed)
				(footprints allowed)
			)
			(placement
				(enabled no)
				(sheetname "")
			)
			(fill
				(thermal_gap 0.5)
				(thermal_bridge_width 0.5)
				(island_removal_mode 0)
			)
			(polygon
				(pts
					(xy 257.6957 -13.208) (xy 257.1877 -13.208) (xy 257.1877 -12.446) (xy 257.6957 -12.446)
				)
			)
		)
	)
	(footprint ""
		(layer "B.Cu")
		(at 459.73873 -18.55724)
		(property "Reference" "C2T6"
			(at 0 0 0)
			(layer "B.SilkS")
			(hide yes)
			(effects
				(font
					(size 1.27 1.27)
				)
				(justify mirror)
			)
		)
		(property "Value" ""
			(at 0 0 0)
			(layer "B.Fab")
			(effects
				(font
					(size 1.27 1.27)
				)
				(justify mirror)
			)
		)
		(duplicate_pad_numbers_are_jumpers no)
		(fp_rect
			(start 0.7239 -0.2159)
			(end -0.7239 1.9939)
			(stroke
				(width 0)
				(type default)
			)
			(fill no)
			(layer "B.CrtYd")
		)
		(fp_line
			(start -0.7239 -0.2159)
			(end 0.7239 -0.2159)
			(stroke
				(width 0.1)
				(type default)
			)
			(layer "B.Fab")
		)
		(fp_line
			(start -0.7239 1.9939)
			(end -0.7239 -0.2159)
			(stroke
				(width 0.1)
				(type default)
			)
			(layer "B.Fab")
		)
		(fp_line
			(start 0.7239 -0.2159)
			(end 0.7239 1.9939)
			(stroke
				(width 0.1)
				(type default)
			)
			(layer "B.Fab")
		)
		(fp_line
			(start 0.7239 1.9939)
			(end -0.7239 1.9939)
			(stroke
				(width 0.1)
				(type default)
			)
			(layer "B.Fab")
		)
		(pad "1" smd rect
			(at 0 0 180)
			(size 1.27 1.016)
			(layers "B.Cu" "B.Mask" "B.Paste")
			(net "P3V3_STBY")
		)
		(pad "2" smd rect
			(at 0 1.778 180)
			(size 1.27 1.016)
			(layers "B.Cu" "B.Mask" "B.Paste")
			(net "GND")
		)
		(zone
			(layer "B.Cu")
			(hatch none 0.5)
			(connect_pads
				(clearance 0)
			)
			(min_thickness 0.25)
			(keepout
				(tracks not_allowed)
				(vias allowed)
				(pads allowed)
				(copperpour not_allowed)
				(footprints allowed)
			)
			(placement
				(enabled no)
				(sheetname "")
			)
			(fill
				(thermal_gap 0.5)
				(thermal_bridge_width 0.5)
				(island_removal_mode 0)
			)
			(polygon
				(pts
					(xy 460.37373 -18.04924) (xy 459.10373 -18.04924) (xy 459.10373 -17.28724) (xy 460.37373 -17.28724)
				)
			)
		)
	)
)
